# BASEBOARD_FAB2 (Tioga Pass) — schematic netlist excerpt (pin names and nets, part order shuffled) for the footprints in the layout excerpt that follows; sources: Cadence DE-HDL packaged netlist, KiCad conversion of Wiwynn_Tioga_Pass_MB.brd

R25W124  RES  150.0 1% CHIP  pkg 0402  page 144 : A = BMC_VGA_GREEN ; B = GND
C25W44  CAP  1.0UF 16V 10% X6S  pkg 0402  page 149 : A = VCC_D_3V3 ; B = GND
C5U3  CAP_A  47UF 4V 20% X5R  pkg 0603V  page 217 : A = PVDDQ_ABC ; B = GND

(kicad_pcb
	(version 20260206)
	(generator "pcbnew")
	(generator_version "10.0")
	(general
		(thickness 1.6)
		(legacy_teardrops no)
	)
	(paper "A4")
	(title_block
		(title "Wiwynn_Tioga_Pass_MB.brd")
		(comment 1 "Tioga Pass / footprints 3558-3560 of 4770")
	)
	(layers
		(0 "F.Cu" signal "TOP")
		(4 "In1.Cu" signal "L2GND")
		(6 "In2.Cu" signal "L3")
		(8 "In3.Cu" signal "L4GND")
		(10 "In4.Cu" signal "L5")
		(12 "In5.Cu" signal "L6GND")
		(14 "In6.Cu" signal "L7VCC")
		(16 "In7.Cu" signal "L8VCC")
		(18 "In8.Cu" signal "L9GND")
		(20 "In9.Cu" signal "L10")
		(22 "In10.Cu" signal "L11GND")
		(24 "In11.Cu" signal "L12")
		(26 "In12.Cu" signal "L13GND")
		(2 "B.Cu" signal "BOTTOM")
		(9 "F.Adhes" user "F.Adhesive")
		(11 "B.Adhes" user "B.Adhesive")
		(13 "F.Paste" user "Package Geometry/Pastemask Top")
		(15 "B.Paste" user "Package Geometry/Pastemask Bottom")
		(5 "F.SilkS" user "Ref Des/Silkscreen Top")
		(7 "B.SilkS" user "Ref Des/Silkscreen Bottom")
		(1 "F.Mask" user "Board Geometry/Soldermask Top")
		(3 "B.Mask" user "Board Geometry/Soldermask Bottom")
		(17 "Dwgs.User" user "User.Drawings")
		(19 "Cmts.User" user "User.Comments")
		(21 "Eco1.User" user "User.Eco1")
		(23 "Eco2.User" user "User.Eco2")
		(25 "Edge.Cuts" user "Board Geometry/Outline")
		(27 "Margin" user)
		(31 "F.CrtYd" user "Package Geometry/Place Bound Top")
		(29 "B.CrtYd" user "Package Geometry/Place Bound Bottom")
		(35 "F.Fab" user "Ref Des/Assembly Top")
		(33 "B.Fab" user "Ref Des/Assembly Bottom")
	)
	(footprint ""
		(layer "B.Cu")
		(at 416.9664 -22.987 180)
		(property "Reference" "R25W124"
			(at 0.8382 -0.67818 180)
			(unlocked yes)
			(layer "B.SilkS")
			(effects
				(font
					(size 0.4064 0.254)
					(thickness 0.1524)
				)
				(justify left mirror)
			)
		)
		(property "Value" ""
			(at 0 0 0)
			(layer "B.Fab")
			(effects
				(font
					(size 1.27 1.27)
				)
				(justify mirror)
			)
		)
		(duplicate_pad_numbers_are_jumpers no)
		(fp_poly
			(pts
				(xy 0.2794 -0.1016) (xy -0.2794 -0.1016) (xy -0.2794 0.9906) (xy 0.2794 0.9906)
			)
			(stroke
				(width 0)
				(type default)
			)
			(fill no)
			(layer "B.CrtYd")
		)
		(fp_line
			(start 0.2794 0.9906)
			(end -0.2794 0.9906)
			(stroke
				(width 0.1)
				(type default)
			)
			(layer "B.Fab")
		)
		(fp_line
			(start 0.2794 -0.1016)
			(end 0.2794 0.9906)
			(stroke
				(width 0.1)
				(type default)
			)
			(layer "B.Fab")
		)
		(fp_line
			(start -0.2794 0.9906)
			(end -0.2794 -0.1016)
			(stroke
				(width 0.1)
				(type default)
			)
			(layer "B.Fab")
		)
		(fp_line
			(start -0.2794 -0.1016)
			(end 0.2794 -0.1016)
			(stroke
				(width 0.1)
				(type default)
			)
			(layer "B.Fab")
		)
		(pad "1" smd rect
			(at 0 0)
			(size 0.508 0.508)
			(layers "B.Cu" "B.Mask" "B.Paste")
			(net "BMC_VGA_GREEN")
		)
		(pad "2" smd rect
			(at 0 0.889)
			(size 0.508 0.508)
			(layers "B.Cu" "B.Mask" "B.Paste")
			(net "GND")
		)
		(zone
			(layer "B.Cu")
			(hatch none 0.5)
			(connect_pads
				(clearance 0)
			)
			(min_thickness 0.25)
			(keepout
				(tracks not_allowed)
				(vias allowed)
				(pads allowed)
				(copperpour not_allowed)
				(footprints allowed)
			)
			(placement
				(enabled no)
				(sheetname "")
			)
			(fill
				(thermal_gap 0.5)
				(thermal_bridge_width 0.5)
				(island_removal_mode 0)
			)
			(polygon
				(pts
					(xy 416.7124 -23.622) (xy 417.2204 -23.622) (xy 417.2204 -23.241) (xy 416.7124 -23.241)
				)
			)
		)
		(zone
			(layer "B.Cu")
			(hatch none 0.5)
			(connect_pads
				(clearance 0)
			)
			(min_thickness 0.25)
			(keepout
				(tracks allowed)
				(vias not_allowed)
				(pads allowed)
				(copperpour not_allowed)
				(footprints allowed)
			)
			(placement
				(enabled no)
				(sheetname "")
			)
			(fill
				(thermal_gap 0.5)
				(thermal_bridge_width 0.5)
				(island_removal_mode 0)
			)
			(polygon
				(pts
					(xy 416.7124 -23.241) (xy 417.2204 -23.241) (xy 417.2204 -23.622) (xy 416.7124 -23.622)
				)
			)
		)
	)
	(footprint ""
		(layer "B.Cu")
		(at 417.223194 -38.2905 90)
		(property "Reference" "C25W44"
			(at 0.8382 -0.67818 90)
			(unlocked yes)
			(layer "B.SilkS")
			(effects
				(font
					(size 0.4064 0.254)
					(thickness 0.1524)
				)
				(justify left mirror)
			)
		)
		(property "Value" ""
			(at 0 0 90)
			(layer "B.Fab")
			(effects
				(font
					(size 1.27 1.27)
				)
				(justify mirror)
			)
		)
		(duplicate_pad_numbers_are_jumpers no)
		(fp_poly
			(pts
				(xy -0.3048 -0.1016) (xy -0.3048 0.9906) (xy 0.3048 0.9906) (xy 0.3048 -0.1016)
			)
			(stroke
				(width 0)
				(type default)
			)
			(fill no)
			(layer "B.CrtYd")
		)
		(fp_line
			(start 0.3048 -0.1016)
			(end 0.3048 0.9906)
			(stroke
				(width 0.1)
				(type default)
			)
			(layer "B.Fab")
		)
		(fp_line
			(start -0.3048 -0.1016)
			(end 0.3048 -0.1016)
			(stroke
				(width 0.1)
				(type default)
			)
			(layer "B.Fab")
		)
		(fp_line
			(start 0.3048 0.9906)
			(end -0.3048 0.9906)
			(stroke
				(width 0.1)
				(type default)
			)
			(layer "B.Fab")
		)
		(fp_line
			(start -0.3048 0.9906)
			(end -0.3048 -0.1016)
			(stroke
				(width 0.1)
				(type default)
			)
			(layer "B.Fab")
		)
		(pad "1" smd rect
			(at 0 0 270)
			(size 0.508 0.508)
			(layers "B.Cu" "B.Mask" "B.Paste")
			(net "VCC_D_3V3")
		)
		(pad "2" smd rect
			(at 0 0.889 270)
			(size 0.508 0.508)
			(layers "B.Cu" "B.Mask" "B.Paste")
			(net "GND")
		)
		(zone
			(layer "B.Cu")
			(hatch none 0.5)
			(connect_pads
				(clearance 0)
			)
			(min_thickness 0.25)
			(keepout
				(tracks allowed)
				(vias not_allowed)
				(pads allowed)
				(copperpour not_allowed)
				(footprints allowed)
			)
			(placement
				(enabled no)
				(sheetname "")
			)
			(fill
				(thermal_gap 0.5)
				(thermal_bridge_width 0.5)
				(island_removal_mode 0)
			)
			(polygon
				(pts
					(xy 417.477194 -38.5445) (xy 417.477194 -38.0365) (xy 417.858194 -38.0365) (xy 417.858194 -38.5445)
				)
			)
		)
		(zone
			(layer "B.Cu")
			(hatch none 0.5)
			(connect_pads
				(clearance 0)
			)
			(min_thickness 0.25)
			(keepout
				(tracks not_allowed)
				(vias allowed)
				(pads allowed)
				(copperpour not_allowed)
				(footprints allowed)
			)
			(placement
				(enabled no)
				(sheetname "")
			)
			(fill
				(thermal_gap 0.5)
				(thermal_bridge_width 0.5)
				(island_removal_mode 0)
			)
			(polygon
				(pts
					(xy 417.858194 -38.5445) (xy 417.858194 -38.0365) (xy 417.477194 -38.0365) (xy 417.477194 -38.5445)
				)
			)
		)
	)
	(footprint ""
		(layer "B.Cu")
		(at 272.861532 -8.1534 90)
		(property "Reference" "C5U3"
			(at -1.848866 0.752348 90)
			(unlocked yes)
			(layer "B.SilkS")
			(effects
				(font
					(size 1.27 0.9652)
					(thickness 0.1524)
				)
				(justify mirror)
			)
		)
		(property "Value" ""
			(at 0 0 90)
			(layer "B.Fab")
			(effects
				(font
					(size 1.27 1.27)
				)
				(justify mirror)
			)
		)
		(duplicate_pad_numbers_are_jumpers no)
		(fp_rect
			(start 0.500126 1.598422)
			(end -0.500126 -0.201422)
			(stroke
				(width 0)
				(type default)
			)
			(fill no)
			(layer "B.CrtYd")
		)
		(fp_line
			(start 0.500126 -0.201422)
			(end -0.500126 -0.201422)
			(stroke
				(width 0.1)
				(type default)
			)
			(layer "B.Fab")
		)
		(fp_line
			(start -0.500126 -0.201422)
			(end -0.500126 1.598422)
			(stroke
				(width 0.1)
				(type default)
			)
			(layer "B.Fab")
		)
		(fp_line
			(start 0.500126 1.598422)
			(end 0.500126 -0.201422)
			(stroke
				(width 0.1)
				(type default)
			)
			(layer "B.Fab")
		)
		(fp_line
			(start -0.500126 1.598422)
			(end 0.500126 1.598422)
			(stroke
				(width 0.1)
				(type default)
			)
			(layer "B.Fab")
		)
		(pad "1" smd rect
			(at 0 0)
			(size 0.889 0.9906)
			(layers "B.Cu" "B.Mask" "B.Paste")
			(net "PVDDQ_ABC")
		)
		(pad "2" smd rect
			(at 0 1.397)
			(size 0.889 0.9906)
			(layers "B.Cu" "B.Mask" "B.Paste")
			(net "GND")
		)
		(zone
			(layer "B.Cu")
			(hatch none 0.5)
			(connect_pads
				(clearance 0)
			)
			(min_thickness 0.25)
			(keepout
				(tracks not_allowed)
				(vias allowed)
				(pads allowed)
				(copperpour not_allowed)
				(footprints allowed)
			)
			(placement
				(enabled no)
				(sheetname "")
			)
			(fill
				(thermal_gap 0.5)
				(thermal_bridge_width 0.5)
				(island_removal_mode 0)
			)
			(polygon
				(pts
					(xy 273.814032 -8.6487) (xy 273.306032 -8.6487) (xy 273.306032 -7.6581) (xy 273.814032 -7.6581)
				)
			)
		)
		(zone
			(layer "B.Cu")
			(hatch none 0.5)
			(connect_pads
				(clearance 0)
			)
			(min_thickness 0.25)
			(keepout
				(tracks allowed)
				(vias not_allowed)
				(pads allowed)
				(copperpour not_allowed)
				(footprints allowed)
			)
			(placement
				(enabled no)
				(sheetname "")
			)
			(fill
				(thermal_gap 0.5)
				(thermal_bridge_width 0.5)
				(island_removal_mode 0)
			)
			(polygon
				(pts
					(xy 273.814032 -8.6487) (xy 273.306032 -8.6487) (xy 273.306032 -7.6581) (xy 273.814032 -7.6581)
				)
			)
		)
	)
)
